(kicad_pcb
	(version 20241229)
	(generator "pcbnew")
	(generator_version "9.0")
	(general
		(thickness 1.62)
		(legacy_teardrops no)
	)
	(paper "A3")
	(title_block
		(title "COM Express 7 Baseboard")
		(date "2025-02-04")
		(rev "1.1.2")
		(company "Antmicro Ltd")
		(comment 1 "www.antmicro.com")
		(comment 9 "footprints 209-214 of 802")
	)
	(layers
		(0 "F.Cu" signal)
		(4 "In1.Cu" signal)
		(6 "In2.Cu" signal)
		(8 "In3.Cu" signal)
		(10 "In4.Cu" signal)
		(12 "In5.Cu" signal)
		(14 "In6.Cu" signal)
		(2 "B.Cu" signal)
		(9 "F.Adhes" user "F.Adhesive")
		(11 "B.Adhes" user "B.Adhesive")
		(13 "F.Paste" user)
		(15 "B.Paste" user)
		(5 "F.SilkS" user "F.Silkscreen")
		(7 "B.SilkS" user "B.Silkscreen")
		(1 "F.Mask" user)
		(3 "B.Mask" user)
		(17 "Dwgs.User" user "User.Drawings")
		(19 "Cmts.User" user "User.Comments")
		(21 "Eco1.User" user "User.Eco1")
		(23 "Eco2.User" user "User.Eco2")
		(25 "Edge.Cuts" user)
		(27 "Margin" user)
		(31 "F.CrtYd" user "F.Courtyard")
		(29 "B.CrtYd" user "B.Courtyard")
		(35 "F.Fab" user)
		(33 "B.Fab" user)
	)
	(footprint "antmicro-footprints:R_0402_1005Metric"
		(layer "F.Cu")
		(at 132.9 81.760001 -90)
		(descr "Resistor SMD 0402")
		(tags "resistor SMD 0402")
		(property "Reference" "R234"
			(at -3.650001 -0.45 90)
			(layer "F.SilkS")
			(effects
				(font
					(size 0.7 0.7)
					(thickness 0.15)
				)
				(justify right bottom)
			)
		)
		(property "Value" "R_0R_0402"
			(at -1.011843 1.772047 90)
			(layer "F.Fab")
			(effects
				(font
					(size 0.7 0.7)
					(thickness 0.15)
				)
				(justify right bottom)
			)
		)
		(property "Datasheet" "https://industrial.panasonic.com/cdbs/www-data/pdf/RDA0000/AOA0000C301.pdf"
			(at 0 0 270)
			(layer "F.Fab")
			(hide yes)
			(effects
				(font
					(size 1.27 1.27)
					(thickness 0.15)
				)
			)
		)
		(property "Author" "Antmicro"
			(at 51.139999 214.660001 0)
			(layer "F.Fab")
			(hide yes)
			(effects
				(font
					(size 1 1)
					(thickness 0.15)
				)
			)
		)
		(property "Current" "1A"
			(at 51.139999 214.660001 0)
			(layer "F.Fab")
			(hide yes)
			(effects
				(font
					(size 1 1)
					(thickness 0.15)
				)
			)
		)
		(property "License" "Apache-2.0"
			(at 51.139999 214.660001 0)
			(layer "F.Fab")
			(hide yes)
			(effects
				(font
					(size 1 1)
					(thickness 0.15)
				)
			)
		)
		(property "MPN" "ERJ2GE0R00X"
			(at 51.139999 214.660001 0)
			(layer "F.Fab")
			(hide yes)
			(effects
				(font
					(size 1 1)
					(thickness 0.15)
				)
			)
		)
		(property "Manufacturer" "Panasonic"
			(at 51.139999 214.660001 0)
			(layer "F.Fab")
			(hide yes)
			(effects
				(font
					(size 1 1)
					(thickness 0.15)
				)
			)
		)
		(property "Public" "False"
			(at 51.139999 214.660001 0)
			(layer "F.Fab")
			(hide yes)
			(effects
				(font
					(size 1 1)
					(thickness 0.15)
				)
			)
		)
		(property "Tolerance" ""
			(at 51.139999 214.660001 0)
			(layer "F.Fab")
			(hide yes)
			(effects
				(font
					(size 1 1)
					(thickness 0.15)
				)
			)
		)
		(property "Val" "0R"
			(at 51.139999 214.660001 0)
			(layer "F.Fab")
			(hide yes)
			(effects
				(font
					(size 1 1)
					(thickness 0.15)
				)
			)
		)
		(sheetname "GPIO expander")
		(sheetfile "gpio_exp.kicad_sch")
		(attr smd)
		(fp_rect
			(start -0.925 -0.47)
			(end 0.925 0.47)
			(stroke
				(width 0.05)
				(type default)
			)
			(fill no)
			(layer "F.CrtYd")
		)
		(fp_rect
			(start -0.5 -0.25)
			(end 0.5 0.25)
			(stroke
				(width 0.15)
				(type solid)
			)
			(fill no)
			(layer "F.Fab")
		)
		(pad "1" smd roundrect
			(at -0.48 0 270)
			(size 0.59 0.64)
			(layers "F.Cu" "F.Mask" "F.Paste")
			(roundrect_rratio 0.25)
			(net 357 "/Com Express 7 MGMT/SMBus.SCL")
			(pintype "passive")
			(teardrops
				(best_length_ratio 0.2)
				(max_length 1)
				(best_width_ratio 0.9)
				(max_width 2)
				(curved_edges yes)
				(filter_ratio 0.9)
				(enabled yes)
				(allow_two_segments yes)
				(prefer_zone_connections yes)
			)
		)
		(pad "2" smd roundrect
			(at 0.48 0 270)
			(size 0.59 0.64)
			(layers "F.Cu" "F.Mask" "F.Paste")
			(roundrect_rratio 0.25)
			(net 635 "Net-(U41-SCL)")
			(pintype "passive")
			(teardrops
				(best_length_ratio 0.2)
				(max_length 1)
				(best_width_ratio 0.9)
				(max_width 2)
				(curved_edges yes)
				(filter_ratio 0.9)
				(enabled yes)
				(allow_two_segments yes)
				(prefer_zone_connections yes)
			)
		)
	)
	(footprint "antmicro-footprints:R_0402_1005Metric"
		(layer "F.Cu")
		(at 251.625 132.36 90)
		(descr "Resistor SMD 0402")
		(tags "resistor SMD 0402")
		(property "Reference" "R167"
			(at -6.75 0.475 90)
			(layer "F.SilkS")
			(effects
				(font
					(size 0.7 0.7)
					(thickness 0.15)
				)
				(justify left bottom)
			)
		)
		(property "Value" "R_10k_0402"
			(at -1.011843 1.772047 90)
			(layer "F.Fab")
			(effects
				(font
					(size 0.7 0.7)
					(thickness 0.15)
				)
				(justify left bottom)
			)
		)
		(property "Datasheet" "https://www.bourns.com/docs/product-datasheets/cr.pdf"
			(at 0 0 90)
			(layer "F.Fab")
			(hide yes)
			(effects
				(font
					(size 1.27 1.27)
					(thickness 0.15)
				)
			)
		)
		(property "Author" "Antmicro"
			(at 383.985 -119.265 0)
			(layer "F.Fab")
			(hide yes)
			(effects
				(font
					(size 1 1)
					(thickness 0.15)
				)
			)
		)
		(property "License" "Apache-2.0"
			(at 383.985 -119.265 0)
			(layer "F.Fab")
			(hide yes)
			(effects
				(font
					(size 1 1)
					(thickness 0.15)
				)
			)
		)
		(property "MPN" "CR0402-FX-1002GLF"
			(at 383.985 -119.265 0)
			(layer "F.Fab")
			(hide yes)
			(effects
				(font
					(size 1 1)
					(thickness 0.15)
				)
			)
		)
		(property "Manufacturer" "Bourns"
			(at 383.985 -119.265 0)
			(layer "F.Fab")
			(hide yes)
			(effects
				(font
					(size 1 1)
					(thickness 0.15)
				)
			)
		)
		(property "Public" "False"
			(at 383.985 -119.265 0)
			(layer "F.Fab")
			(hide yes)
			(effects
				(font
					(size 1 1)
					(thickness 0.15)
				)
			)
		)
		(property "Tolerance" "1%"
			(at 383.985 -119.265 0)
			(layer "F.Fab")
			(hide yes)
			(effects
				(font
					(size 1 1)
					(thickness 0.15)
				)
			)
		)
		(property "Val" "10k"
			(at 383.985 -119.265 0)
			(layer "F.Fab")
			(hide yes)
			(effects
				(font
					(size 1 1)
					(thickness 0.15)
				)
			)
		)
		(sheetname "Com Express 7 MGMT")
		(sheetfile "com_express_7_mgmt.kicad_sch")
		(attr smd)
		(fp_rect
			(start -0.925 -0.47)
			(end 0.925 0.47)
			(stroke
				(width 0.05)
				(type default)
			)
			(fill no)
			(layer "F.CrtYd")
		)
		(fp_rect
			(start -0.5 -0.25)
			(end 0.5 0.25)
			(stroke
				(width 0.15)
				(type solid)
			)
			(fill no)
			(layer "F.Fab")
		)
		(pad "1" smd roundrect
			(at -0.48 0 90)
			(size 0.59 0.64)
			(layers "F.Cu" "F.Mask" "F.Paste")
			(roundrect_rratio 0.25)
			(net 136 "/Com Express 7 MGMT/~{TYPE0}")
			(pintype "passive")
			(teardrops
				(best_length_ratio 0.2)
				(max_length 1)
				(best_width_ratio 0.9)
				(max_width 2)
				(curved_edges yes)
				(filter_ratio 0.9)
				(enabled yes)
				(allow_two_segments yes)
				(prefer_zone_connections yes)
			)
		)
		(pad "2" smd roundrect
			(at 0.48 0 90)
			(size 0.59 0.64)
			(layers "F.Cu" "F.Mask" "F.Paste")
			(roundrect_rratio 0.25)
			(net 73 "+3V3_AON")
			(pintype "passive")
			(teardrops
				(best_length_ratio 0.2)
				(max_length 1)
				(best_width_ratio 0.9)
				(max_width 2)
				(curved_edges yes)
				(filter_ratio 0.9)
				(enabled yes)
				(allow_two_segments yes)
				(prefer_zone_connections yes)
			)
		)
	)
	(footprint "antmicro-footprints:R_0402_1005Metric"
		(layer "F.Cu")
		(at 247.825 132.36 90)
		(descr "Resistor SMD 0402")
		(tags "resistor SMD 0402")
		(property "Reference" "R168"
			(at -3.7 0.425 90)
			(layer "F.SilkS")
			(effects
				(font
					(size 0.7 0.7)
					(thickness 0.15)
				)
				(justify left bottom)
			)
		)
		(property "Value" "R_10k_0402"
			(at -1.011843 1.772047 90)
			(layer "F.Fab")
			(effects
				(font
					(size 0.7 0.7)
					(thickness 0.15)
				)
				(justify left bottom)
			)
		)
		(property "Datasheet" "https://www.bourns.com/docs/product-datasheets/cr.pdf"
			(at 0 0 90)
			(layer "F.Fab")
			(hide yes)
			(effects
				(font
					(size 1.27 1.27)
					(thickness 0.15)
				)
			)
		)
		(property "Author" "Antmicro"
			(at 380.185 -115.465 0)
			(layer "F.Fab")
			(hide yes)
			(effects
				(font
					(size 1 1)
					(thickness 0.15)
				)
			)
		)
		(property "License" "Apache-2.0"
			(at 380.185 -115.465 0)
			(layer "F.Fab")
			(hide yes)
			(effects
				(font
					(size 1 1)
					(thickness 0.15)
				)
			)
		)
		(property "MPN" "CR0402-FX-1002GLF"
			(at 380.185 -115.465 0)
			(layer "F.Fab")
			(hide yes)
			(effects
				(font
					(size 1 1)
					(thickness 0.15)
				)
			)
		)
		(property "Manufacturer" "Bourns"
			(at 380.185 -115.465 0)
			(layer "F.Fab")
			(hide yes)
			(effects
				(font
					(size 1 1)
					(thickness 0.15)
				)
			)
		)
		(property "Public" "False"
			(at 380.185 -115.465 0)
			(layer "F.Fab")
			(hide yes)
			(effects
				(font
					(size 1 1)
					(thickness 0.15)
				)
			)
		)
		(property "Tolerance" "1%"
			(at 380.185 -115.465 0)
			(layer "F.Fab")
			(hide yes)
			(effects
				(font
					(size 1 1)
					(thickness 0.15)
				)
			)
		)
		(property "Val" "10k"
			(at 380.185 -115.465 0)
			(layer "F.Fab")
			(hide yes)
			(effects
				(font
					(size 1 1)
					(thickness 0.15)
				)
			)
		)
		(sheetname "Com Express 7 MGMT")
		(sheetfile "com_express_7_mgmt.kicad_sch")
		(attr smd)
		(fp_rect
			(start -0.925 -0.47)
			(end 0.925 0.47)
			(stroke
				(width 0.05)
				(type default)
			)
			(fill no)
			(layer "F.CrtYd")
		)
		(fp_rect
			(start -0.5 -0.25)
			(end 0.5 0.25)
			(stroke
				(width 0.15)
				(type solid)
			)
			(fill no)
			(layer "F.Fab")
		)
		(pad "1" smd roundrect
			(at -0.48 0 90)
			(size 0.59 0.64)
			(layers "F.Cu" "F.Mask" "F.Paste")
			(roundrect_rratio 0.25)
			(net 434 "/Com Express 7 MGMT/~{TYPE1}")
			(pintype "passive")
			(teardrops
				(best_length_ratio 0.2)
				(max_length 1)
				(best_width_ratio 0.9)
				(max_width 2)
				(curved_edges yes)
				(filter_ratio 0.9)
				(enabled yes)
				(allow_two_segments yes)
				(prefer_zone_connections yes)
			)
		)
		(pad "2" smd roundrect
			(at 0.48 0 90)
			(size 0.59 0.64)
			(layers "F.Cu" "F.Mask" "F.Paste")
			(roundrect_rratio 0.25)
			(net 73 "+3V3_AON")
			(pintype "passive")
			(teardrops
				(best_length_ratio 0.2)
				(max_length 1)
				(best_width_ratio 0.9)
				(max_width 2)
				(curved_edges yes)
				(filter_ratio 0.9)
				(enabled yes)
				(allow_two_segments yes)
				(prefer_zone_connections yes)
			)
		)
	)
	(footprint "antmicro-footprints:TP_SMD_0.75mm"
		(layer "F.Cu")
		(at 151.8 128.71)
		(property "Reference" "TP60"
			(at 0.4 -3.3 90)
			(layer "F.SilkS")
			(effects
				(font
					(size 0.7 0.7)
					(thickness 0.15)
				)
				(justify left bottom)
			)
		)
		(property "Value" "TP_0.75mm_SMD"
			(at 0 1.2 0)
			(layer "F.Fab")
			(effects
				(font
					(size 0.7 0.7)
					(thickness 0.15)
				)
				(justify left bottom)
			)
		)
		(property "Author" "Antmicro"
			(at 0 0 0)
			(layer "F.Fab")
			(hide yes)
			(effects
				(font
					(size 1 1)
					(thickness 0.15)
				)
			)
		)
		(property "License" "Apache-2.0"
			(at 0 0 0)
			(layer "F.Fab")
			(hide yes)
			(effects
				(font
					(size 1 1)
					(thickness 0.15)
				)
			)
		)
		(property "MPN" ""
			(at 0 0 0)
			(layer "F.Fab")
			(hide yes)
			(effects
				(font
					(size 1 1)
					(thickness 0.15)
				)
			)
		)
		(property "Manufacturer" ""
			(at 0 0 0)
			(layer "F.Fab")
			(hide yes)
			(effects
				(font
					(size 1 1)
					(thickness 0.15)
				)
			)
		)
		(property "Public" "False"
			(at 0 0 0)
			(layer "F.Fab")
			(hide yes)
			(effects
				(font
					(size 1 1)
					(thickness 0.15)
				)
			)
		)
		(sheetname "KR to SFI #1")
		(sheetfile "kr_sfi.kicad_sch")
		(attr exclude_from_pos_files exclude_from_bom)
		(fp_circle
			(center 0 0)
			(end 0.475 0)
			(stroke
				(width 0.05)
				(type default)
			)
			(fill no)
			(layer "F.CrtYd")
		)
		(pad "1" smd circle
			(at 0 0)
			(size 0.75 0.75)
			(layers "F.Cu" "F.Mask")
			(net 723 "/2xSFP+/KR to SFI #1/TDO")
			(pinfunction "1")
			(pintype "passive")
			(teardrops
				(best_length_ratio 0.4)
				(max_length 1)
				(best_width_ratio 0.9)
				(max_width 2)
				(curved_edges yes)
				(filter_ratio 0.9)
				(enabled yes)
				(allow_two_segments yes)
				(prefer_zone_connections yes)
			)
		)
	)
	(footprint "antmicro-footprints:VSSOP-8_2.3x2mm_P0.5mm"
		(layer "F.Cu")
		(at 308.275 81.91 -90)
		(property "Reference" "U38"
			(at 2.8 -1.125 180)
			(layer "F.SilkS")
			(effects
				(font
					(size 0.7 0.7)
					(thickness 0.15)
				)
				(justify right bottom)
			)
		)
		(property "Value" "74AUP2G132"
			(at 0 2.258 90)
			(layer "F.Fab")
			(effects
				(font
					(size 0.7 0.7)
					(thickness 0.15)
				)
				(justify right bottom)
			)
		)
		(property "Datasheet" "https://assets.nexperia.com/documents/data-sheet/74AUP2G132.pdf"
			(at 0 0 270)
			(layer "F.Fab")
			(hide yes)
			(effects
				(font
					(size 1.27 1.27)
					(thickness 0.15)
				)
			)
		)
		(property "Author" "Antmicro"
			(at 226.365 390.185 0)
			(layer "F.Fab")
			(hide yes)
			(effects
				(font
					(size 1 1)
					(thickness 0.15)
				)
			)
		)
		(property "License" "Apache-2.0"
			(at 226.365 390.185 0)
			(layer "F.Fab")
			(hide yes)
			(effects
				(font
					(size 1 1)
					(thickness 0.15)
				)
			)
		)
		(property "MPN" "74AUP2G132"
			(at 226.365 390.185 0)
			(layer "F.Fab")
			(hide yes)
			(effects
				(font
					(size 1 1)
					(thickness 0.15)
				)
			)
		)
		(property "Manufacturer" "Nexperia"
			(at 226.365 390.185 0)
			(layer "F.Fab")
			(hide yes)
			(effects
				(font
					(size 1 1)
					(thickness 0.15)
				)
			)
		)
		(sheetname "PCIe misc")
		(sheetfile "pcie_misc.kicad_sch")
		(attr smd)
		(fp_line
			(start 0.825 1.007)
			(end -0.82 1.007)
			(stroke
				(width 0.15)
				(type solid)
			)
			(layer "F.SilkS")
		)
		(fp_line
			(start -0.82 -0.992)
			(end 0.825 -0.992)
			(stroke
				(width 0.15)
				(type solid)
			)
			(layer "F.SilkS")
		)
		(fp_circle
			(center -1.402 -1.192)
			(end -1.352 -1.192)
			(stroke
				(width 0.15)
				(type solid)
			)
			(fill yes)
			(layer "F.SilkS")
		)
		(fp_rect
			(start 1.8 1.35)
			(end -1.8 -1.35)
			(stroke
				(width 0.05)
				(type solid)
			)
			(fill no)
			(layer "F.CrtYd")
		)
		(fp_line
			(start -0.7 -0.99)
			(end -1.14 -0.55)
			(stroke
				(width 0.15)
				(type solid)
			)
			(layer "F.Fab")
		)
		(fp_rect
			(start -1.147 -0.992)
			(end 1.151 1.007)
			(stroke
				(width 0.15)
				(type solid)
			)
			(fill no)
			(layer "F.Fab")
		)
		(pad "1" smd rect
			(at -1.372 -0.742 270)
			(size 0.75 0.4)
			(layers "F.Cu" "F.Mask" "F.Paste")
			(net 790 "Net-(U38-1A)")
			(pinfunction "1A")
			(pintype "input")
			(teardrops
				(best_length_ratio 0.2)
				(max_length 1)
				(best_width_ratio 0.9)
				(max_width 2)
				(curved_edges yes)
				(filter_ratio 0.9)
				(enabled yes)
				(allow_two_segments yes)
				(prefer_zone_connections yes)
			)
		)
		(pad "2" smd rect
			(at -1.372 -0.244 270)
			(size 0.75 0.3)
			(layers "F.Cu" "F.Mask" "F.Paste")
			(net 790 "Net-(U38-1A)")
			(pinfunction "1B")
			(pintype "input")
			(teardrops
				(best_length_ratio 0.2)
				(max_length 1)
				(best_width_ratio 0.9)
				(max_width 2)
				(curved_edges yes)
				(filter_ratio 0.9)
				(enabled yes)
				(allow_two_segments yes)
				(prefer_zone_connections yes)
			)
		)
		(pad "3" smd rect
			(at -1.372 0.256 270)
			(size 0.75 0.3)
			(layers "F.Cu" "F.Mask" "F.Paste")
			(net 791 "unconnected-(U38-2Y-Pad3)")
			(pinfunction "2Y")
			(pintype "output+no_connect")
			(teardrops
				(best_length_ratio 0.2)
				(max_length 1)
				(best_width_ratio 0.9)
				(max_width 2)
				(curved_edges yes)
				(filter_ratio 0.9)
				(enabled yes)
				(allow_two_segments yes)
				(prefer_zone_connections yes)
			)
		)
		(pad "4" smd rect
			(at -1.372 0.757 270)
			(size 0.75 0.4)
			(layers "F.Cu" "F.Mask" "F.Paste")
			(net 1 "GND")
			(pinfunction "GND")
			(pintype "power_in")
			(teardrops
				(best_length_ratio 0.2)
				(max_length 1)
				(best_width_ratio 0.9)
				(max_width 2)
				(curved_edges yes)
				(filter_ratio 0.9)
				(enabled yes)
				(allow_two_segments yes)
				(prefer_zone_connections yes)
			)
		)
		(pad "5" smd rect
			(at 1.377 0.757 270)
			(size 0.75 0.4)
			(layers "F.Cu" "F.Mask" "F.Paste")
			(net 1 "GND")
			(pinfunction "2A")
			(pintype "input")
			(teardrops
				(best_length_ratio 0.2)
				(max_length 1)
				(best_width_ratio 0.9)
				(max_width 2)
				(curved_edges yes)
				(filter_ratio 0.9)
				(enabled yes)
				(allow_two_segments yes)
				(prefer_zone_connections yes)
			)
		)
		(pad "6" smd rect
			(at 1.377 0.256 270)
			(size 0.75 0.3)
			(layers "F.Cu" "F.Mask" "F.Paste")
			(net 1 "GND")
			(pinfunction "2B")
			(pintype "input")
			(teardrops
				(best_length_ratio 0.2)
				(max_length 1)
				(best_width_ratio 0.9)
				(max_width 2)
				(curved_edges yes)
				(filter_ratio 0.9)
				(enabled yes)
				(allow_two_segments yes)
				(prefer_zone_connections yes)
			)
		)
		(pad "7" smd rect
			(at 1.377 -0.244 270)
			(size 0.75 0.3)
			(layers "F.Cu" "F.Mask" "F.Paste")
			(net 587 "/M.2 key E/SUSCLK")
			(pinfunction "1Y")
			(pintype "output")
			(teardrops
				(best_length_ratio 0.2)
				(max_length 1)
				(best_width_ratio 0.9)
				(max_width 2)
				(curved_edges yes)
				(filter_ratio 0.9)
				(enabled yes)
				(allow_two_segments yes)
				(prefer_zone_connections yes)
			)
		)
		(pad "8" smd rect
			(at 1.377 -0.742 270)
			(size 0.75 0.4)
			(layers "F.Cu" "F.Mask" "F.Paste")
			(net 2 "+3V3")
			(pinfunction "VCC")
			(pintype "power_in")
			(teardrops
				(best_length_ratio 0.2)
				(max_length 1)
				(best_width_ratio 0.9)
				(max_width 2)
				(curved_edges yes)
				(filter_ratio 0.9)
				(enabled yes)
				(allow_two_segments yes)
				(prefer_zone_connections yes)
			)
		)
	)
	(footprint "antmicro-footprints:TP_SMD_0.75mm"
		(layer "F.Cu")
		(at 201.70861 72.802163 -90)
		(property "Reference" "TP100"
			(at 0 -0.6 90)
			(layer "F.SilkS")
			(hide yes)
			(effects
				(font
					(size 0.7 0.7)
					(thickness 0.15)
				)
				(justify right bottom)
			)
		)
		(property "Value" "TP_0.75mm_SMD"
			(at 0 1.2 90)
			(layer "F.Fab")
			(effects
				(font
					(size 0.7 0.7)
					(thickness 0.15)
				)
				(justify right bottom)
			)
		)
		(property "Author" "Antmicro"
			(at 128.906447 274.510773 0)
			(layer "F.Fab")
			(hide yes)
			(effects
				(font
					(size 1 1)
					(thickness 0.15)
				)
			)
		)
		(property "License" "Apache-2.0"
			(at 128.906447 274.510773 0)
			(layer "F.Fab")
			(hide yes)
			(effects
				(font
					(size 1 1)
					(thickness 0.15)
				)
			)
		)
		(property "MPN" ""
			(at 128.906447 274.510773 0)
			(layer "F.Fab")
			(hide yes)
			(effects
				(font
					(size 1 1)
					(thickness 0.15)
				)
			)
		)
		(property "Manufacturer" ""
			(at 128.906447 274.510773 0)
			(layer "F.Fab")
			(hide yes)
			(effects
				(font
					(size 1 1)
					(thickness 0.15)
				)
			)
		)
		(property "Public" "False"
			(at 128.906447 274.510773 0)
			(layer "F.Fab")
			(hide yes)
			(effects
				(font
					(size 1 1)
					(thickness 0.15)
				)
			)
		)
		(sheetname "Power")
		(sheetfile "power.kicad_sch")
		(attr exclude_from_pos_files exclude_from_bom)
		(fp_circle
			(center 0 0)
			(end 0.475 0)
			(stroke
				(width 0.05)
				(type default)
			)
			(fill no)
			(layer "F.CrtYd")
		)
		(pad "1" smd circle
			(at 0 0 270)
			(size 0.75 0.75)
			(layers "F.Cu" "F.Mask")
			(net 74 "+1V0")
			(pinfunction "1")
			(pintype "passive")
			(teardrops
				(best_length_ratio 0.4)
				(max_length 1)
				(best_width_ratio 0.9)
				(max_width 2)
				(curved_edges yes)
				(filter_ratio 0.9)
				(enabled yes)
				(allow_two_segments yes)
				(prefer_zone_connections yes)
			)
		)
	)
)
